(kicad_pcb
	(version 20260206)
	(generator "pcbnew")
	(generator_version "10.0")
	(general
		(thickness 1.6)
		(legacy_teardrops no)
	)
	(paper "A4")
	(title_block
		(title "Bryce Canyon_IOM_IOC_16318-2_OCP.brd")
		(comment 1 "Bryce Canyon / footprints 1521-1528 of 1605")
	)
	(layers
		(0 "F.Cu" signal "TOP")
		(4 "In1.Cu" signal "L2GND")
		(6 "In2.Cu" signal "L3")
		(8 "In3.Cu" signal "L4VCC")
		(10 "In4.Cu" signal "L5VCC")
		(12 "In5.Cu" signal "L6")
		(14 "In6.Cu" signal "L7GND")
		(2 "B.Cu" signal "BOTTOM")
		(9 "F.Adhes" user "F.Adhesive")
		(11 "B.Adhes" user "B.Adhesive")
		(13 "F.Paste" user "Package Geometry/Pastemask Top")
		(15 "B.Paste" user "Package Geometry/Pastemask Bottom")
		(5 "F.SilkS" user "Ref Des/Silkscreen Top")
		(7 "B.SilkS" user "Ref Des/Silkscreen Bottom")
		(1 "F.Mask" user "Board Geometry/Soldermask Top")
		(3 "B.Mask" user "Board Geometry/Soldermask Bottom")
		(17 "Dwgs.User" user "User.Drawings")
		(19 "Cmts.User" user "User.Comments")
		(21 "Eco1.User" user "User.Eco1")
		(23 "Eco2.User" user "User.Eco2")
		(25 "Edge.Cuts" user "Board Geometry/Outline")
		(27 "Margin" user)
		(31 "F.CrtYd" user "Package Geometry/Place Bound Top")
		(29 "B.CrtYd" user "Package Geometry/Place Bound Bottom")
		(35 "F.Fab" user "Ref Des/Assembly Top")
		(33 "B.Fab" user "Ref Des/Assembly Bottom")
	)
	(footprint ""
		(layer "B.Cu")
		(at 61.468 -150.495 180)
		(property "Reference" "R398"
			(at 0 0 0)
			(layer "B.SilkS")
			(hide yes)
			(effects
				(font
					(size 1.27 1.27)
				)
				(justify mirror)
			)
		)
		(property "Value" "4K7R2F-GP"
			(at -0.064008 -3.993896 180)
			(unlocked yes)
			(layer "B.Fab")
			(hide yes)
			(effects
				(font
					(size 1.016 1.016)
					(thickness 0.1524)
				)
				(justify mirror)
			)
		)
		(property "Device Type" "R402H16"
			(at -0.064008 -5.517896 180)
			(unlocked yes)
			(layer "B.Fab")
			(hide yes)
			(effects
				(font
					(size 1.016 1.016)
					(thickness 0.1524)
				)
				(justify mirror)
			)
		)
		(duplicate_pad_numbers_are_jumpers no)
		(fp_line
			(start 0.508 -0.9398)
			(end 0.508 0.9398)
			(stroke
				(width 0.1524)
				(type default)
			)
			(layer "B.SilkS")
		)
		(fp_line
			(start -0.508 -0.9398)
			(end 0.508 -0.9398)
			(stroke
				(width 0.1524)
				(type default)
			)
			(layer "B.SilkS")
		)
		(fp_rect
			(start 0.508 0.9398)
			(end -0.508 -0.9398)
			(stroke
				(width 0)
				(type default)
			)
			(fill no)
			(layer "B.CrtYd")
		)
		(fp_rect
			(start 0.508 0.9398)
			(end -0.508 -0.9398)
			(stroke
				(width 0)
				(type default)
			)
			(fill no)
			(layer "B.Fab")
		)
		(pad "1" smd custom
			(at 0 -0.4445)
			(size 0.1397 0.1397)
			(layers "B.Cu" "B.Mask" "B.Paste")
			(net "GND")
			(options
				(clearance outline)
				(anchor circle)
			)
			(primitives
				(gr_poly
					(pts
						(arc
							(start -0.1778 0.2794)
							(mid -0.249642 0.249642)
							(end -0.2794 0.1778)
						)
						(arc
							(start -0.2794 -0.1778)
							(mid -0.249642 -0.249642)
							(end -0.1778 -0.2794)
						)
						(arc
							(start 0.1778 -0.2794)
							(mid 0.249642 -0.249642)
							(end 0.2794 -0.1778)
						)
						(arc
							(start 0.2794 0.1778)
							(mid 0.249642 0.249642)
							(end 0.1778 0.2794)
						)
					)
					(width 0)
					(fill yes)
				)
			)
		)
		(pad "2" smd custom
			(at 0 0.4445)
			(size 0.1397 0.1397)
			(layers "B.Cu" "B.Mask" "B.Paste")
			(net "MAC2_TXD2")
			(options
				(clearance outline)
				(anchor circle)
			)
			(primitives
				(gr_poly
					(pts
						(arc
							(start -0.1778 0.2794)
							(mid -0.249642 0.249642)
							(end -0.2794 0.1778)
						)
						(arc
							(start -0.2794 -0.1778)
							(mid -0.249642 -0.249642)
							(end -0.1778 -0.2794)
						)
						(arc
							(start 0.1778 -0.2794)
							(mid 0.249642 -0.249642)
							(end 0.2794 -0.1778)
						)
						(arc
							(start 0.2794 0.1778)
							(mid 0.249642 0.249642)
							(end 0.1778 0.2794)
						)
					)
					(width 0)
					(fill yes)
				)
			)
		)
	)
	(footprint ""
		(layer "B.Cu")
		(at 51.40452 -144.26438)
		(property "Reference" "TP78"
			(at 0 0 0)
			(layer "B.SilkS")
			(hide yes)
			(effects
				(font
					(size 1.27 1.27)
				)
				(justify mirror)
			)
		)
		(property "Value" "TPAD28-2-GP"
			(at 0.0127 -1.6637 0)
			(unlocked yes)
			(layer "B.Fab")
			(hide yes)
			(effects
				(font
					(size 1.016 1.016)
					(thickness 0.1524)
				)
				(justify mirror)
			)
		)
		(property "Device Type" "TPAD28"
			(at 0.0127 -3.1877 0)
			(unlocked yes)
			(layer "B.Fab")
			(hide yes)
			(effects
				(font
					(size 1.016 1.016)
					(thickness 0.1524)
				)
				(justify mirror)
			)
		)
		(duplicate_pad_numbers_are_jumpers no)
		(fp_poly
			(pts
				(arc
					(start 0.3556 0)
					(mid -0.3556 0)
					(end 0.3556 0)
				)
			)
			(stroke
				(width 0)
				(type default)
			)
			(fill no)
			(layer "B.CrtYd")
		)
		(fp_poly
			(pts
				(arc
					(start 0.6096 0)
					(mid -0.6096 0)
					(end 0.6096 0)
				)
			)
			(stroke
				(width 0)
				(type default)
			)
			(fill no)
			(layer "B.Fab")
		)
		(pad "1" smd circle
			(at 0 0 180)
			(size 0.7112 0.7112)
			(layers "B.Cu" "B.Mask" "B.Paste")
			(net "JTAG_BMC_TRST_N")
		)
	)
	(footprint ""
		(layer "B.Cu")
		(at 193.501518 -81.153 180)
		(property "Reference" "C297"
			(at 0 0 0)
			(layer "B.SilkS")
			(hide yes)
			(effects
				(font
					(size 1.27 1.27)
				)
				(justify mirror)
			)
		)
		(property "Value" "SCD22U10V1KX-GP"
			(at 2.8321 -1.7399 180)
			(unlocked yes)
			(layer "B.Fab")
			(hide yes)
			(effects
				(font
					(size 1.016 1.016)
					(thickness 0.1524)
				)
				(justify mirror)
			)
		)
		(property "Device Type" "C0201H13"
			(at 2.8321 -3.2639 180)
			(unlocked yes)
			(layer "B.Fab")
			(hide yes)
			(effects
				(font
					(size 1.016 1.016)
					(thickness 0.1524)
				)
				(justify mirror)
			)
		)
		(duplicate_pad_numbers_are_jumpers no)
		(fp_rect
			(start 0.2794 0.6477)
			(end -0.2794 -0.6477)
			(stroke
				(width 0)
				(type default)
			)
			(fill no)
			(layer "B.CrtYd")
		)
		(fp_rect
			(start 0.2794 0.6477)
			(end -0.2794 -0.6477)
			(stroke
				(width 0)
				(type default)
			)
			(fill no)
			(layer "B.Fab")
		)
		(pad "1" smd custom
			(at 0 -0.2794)
			(size 0.0762 0.0762)
			(layers "B.Cu" "B.Mask" "B.Paste")
			(net "PCIE_IOM_TO_COMP_12_DP_C")
			(options
				(clearance outline)
				(anchor circle)
			)
			(primitives
				(gr_poly
					(pts
						(arc
							(start 0.1524 0.127)
							(mid 0.137521 0.162921)
							(end 0.1016 0.1778)
						)
						(arc
							(start -0.1016 0.1778)
							(mid -0.137521 0.162921)
							(end -0.1524 0.127)
						)
						(arc
							(start -0.1524 -0.127)
							(mid -0.137521 -0.162921)
							(end -0.1016 -0.1778)
						)
						(arc
							(start 0.1016 -0.1778)
							(mid 0.137521 -0.162921)
							(end 0.1524 -0.127)
						)
					)
					(width 0)
					(fill yes)
				)
			)
		)
		(pad "2" smd custom
			(at 0 0.2794)
			(size 0.0762 0.0762)
			(layers "B.Cu" "B.Mask" "B.Paste")
			(net "PCIE_IOM_TO_COMP_12_DP")
			(options
				(clearance outline)
				(anchor circle)
			)
			(primitives
				(gr_poly
					(pts
						(arc
							(start 0.1524 0.127)
							(mid 0.137521 0.162921)
							(end 0.1016 0.1778)
						)
						(arc
							(start -0.1016 0.1778)
							(mid -0.137521 0.162921)
							(end -0.1524 0.127)
						)
						(arc
							(start -0.1524 -0.127)
							(mid -0.137521 -0.162921)
							(end -0.1016 -0.1778)
						)
						(arc
							(start 0.1016 -0.1778)
							(mid 0.137521 -0.162921)
							(end 0.1524 -0.127)
						)
					)
					(width 0)
					(fill yes)
				)
			)
		)
	)
	(footprint ""
		(layer "B.Cu")
		(at 52.78628 -144.99844)
		(property "Reference" "TP52"
			(at 0 0 0)
			(layer "B.SilkS")
			(hide yes)
			(effects
				(font
					(size 1.27 1.27)
				)
				(justify mirror)
			)
		)
		(property "Value" "TPAD28-2-GP"
			(at 0.0127 -1.6637 0)
			(unlocked yes)
			(layer "B.Fab")
			(hide yes)
			(effects
				(font
					(size 1.016 1.016)
					(thickness 0.1524)
				)
				(justify mirror)
			)
		)
		(property "Device Type" "TPAD28"
			(at 0.0127 -3.1877 0)
			(unlocked yes)
			(layer "B.Fab")
			(hide yes)
			(effects
				(font
					(size 1.016 1.016)
					(thickness 0.1524)
				)
				(justify mirror)
			)
		)
		(duplicate_pad_numbers_are_jumpers no)
		(fp_poly
			(pts
				(arc
					(start 0.3556 0)
					(mid -0.3556 0)
					(end 0.3556 0)
				)
			)
			(stroke
				(width 0)
				(type default)
			)
			(fill no)
			(layer "B.CrtYd")
		)
		(fp_poly
			(pts
				(arc
					(start 0.6096 0)
					(mid -0.6096 0)
					(end 0.6096 0)
				)
			)
			(stroke
				(width 0)
				(type default)
			)
			(fill no)
			(layer "B.Fab")
		)
		(pad "1" smd circle
			(at 0 0 180)
			(size 0.7112 0.7112)
			(layers "B.Cu" "B.Mask" "B.Paste")
			(net "RMII_BMC_MDIO_R")
		)
	)
	(footprint ""
		(layer "B.Cu")
		(at 199.997822 -72.5932 90)
		(property "Reference" "C361"
			(at 0 0 90)
			(layer "B.SilkS")
			(hide yes)
			(effects
				(font
					(size 1.27 1.27)
				)
				(justify mirror)
			)
		)
		(property "Value" "SCD1U6D3V1KX-GP"
			(at 2.8321 -1.7399 90)
			(unlocked yes)
			(layer "B.Fab")
			(hide yes)
			(effects
				(font
					(size 1.016 1.016)
					(thickness 0.1524)
				)
				(justify mirror)
			)
		)
		(property "Device Type" "C0201H13"
			(at 2.8321 -3.2639 90)
			(unlocked yes)
			(layer "B.Fab")
			(hide yes)
			(effects
				(font
					(size 1.016 1.016)
					(thickness 0.1524)
				)
				(justify mirror)
			)
		)
		(duplicate_pad_numbers_are_jumpers no)
		(fp_rect
			(start 0.2794 0.6477)
			(end -0.2794 -0.6477)
			(stroke
				(width 0)
				(type default)
			)
			(fill no)
			(layer "B.CrtYd")
		)
		(fp_rect
			(start 0.2794 0.6477)
			(end -0.2794 -0.6477)
			(stroke
				(width 0)
				(type default)
			)
			(fill no)
			(layer "B.Fab")
		)
		(pad "1" smd custom
			(at 0 -0.2794 270)
			(size 0.0762 0.0762)
			(layers "B.Cu" "B.Mask" "B.Paste")
			(net "PCE_VDDH")
			(options
				(clearance outline)
				(anchor circle)
			)
			(primitives
				(gr_poly
					(pts
						(arc
							(start 0.1524 0.127)
							(mid 0.137521 0.162921)
							(end 0.1016 0.1778)
						)
						(arc
							(start -0.1016 0.1778)
							(mid -0.137521 0.162921)
							(end -0.1524 0.127)
						)
						(arc
							(start -0.1524 -0.127)
							(mid -0.137521 -0.162921)
							(end -0.1016 -0.1778)
						)
						(arc
							(start 0.1016 -0.1778)
							(mid 0.137521 -0.162921)
							(end 0.1524 -0.127)
						)
					)
					(width 0)
					(fill yes)
				)
			)
		)
		(pad "2" smd custom
			(at 0 0.2794 270)
			(size 0.0762 0.0762)
			(layers "B.Cu" "B.Mask" "B.Paste")
			(net "GND")
			(options
				(clearance outline)
				(anchor circle)
			)
			(primitives
				(gr_poly
					(pts
						(arc
							(start 0.1524 0.127)
							(mid 0.137521 0.162921)
							(end 0.1016 0.1778)
						)
						(arc
							(start -0.1016 0.1778)
							(mid -0.137521 0.162921)
							(end -0.1524 0.127)
						)
						(arc
							(start -0.1524 -0.127)
							(mid -0.137521 -0.162921)
							(end -0.1016 -0.1778)
						)
						(arc
							(start 0.1016 -0.1778)
							(mid 0.137521 -0.162921)
							(end 0.1524 -0.127)
						)
					)
					(width 0)
					(fill yes)
				)
			)
		)
	)
	(footprint ""
		(layer "B.Cu")
		(at 201.236326 -54.938676)
		(property "Reference" "C458"
			(at 0 0 0)
			(layer "B.SilkS")
			(hide yes)
			(effects
				(font
					(size 1.27 1.27)
				)
				(justify mirror)
			)
		)
		(property "Value" "SCD1U16V2KX-3GP"
			(at -1.1811 -2.7051 0)
			(unlocked yes)
			(layer "B.Fab")
			(hide yes)
			(effects
				(font
					(size 1.016 1.016)
					(thickness 0.1524)
				)
				(justify mirror)
			)
		)
		(property "Device Type" "C402H22"
			(at -1.1811 -4.2291 0)
			(unlocked yes)
			(layer "B.Fab")
			(hide yes)
			(effects
				(font
					(size 1.016 1.016)
					(thickness 0.1524)
				)
				(justify mirror)
			)
		)
		(duplicate_pad_numbers_are_jumpers no)
		(fp_rect
			(start 0.4318 0.9525)
			(end -0.4318 -0.9525)
			(stroke
				(width 0)
				(type default)
			)
			(fill no)
			(layer "B.CrtYd")
		)
		(fp_rect
			(start 0.4318 0.9525)
			(end -0.4318 -0.9525)
			(stroke
				(width 0)
				(type default)
			)
			(fill no)
			(layer "B.Fab")
		)
		(pad "1" smd custom
			(at 0 -0.4445 180)
			(size 0.1524 0.1524)
			(layers "B.Cu" "B.Mask" "B.Paste")
			(net "P1V8")
			(options
				(clearance outline)
				(anchor circle)
			)
			(primitives
				(gr_poly
					(pts
						(arc
							(start 0.3048 0.2032)
							(mid 0.275042 0.275042)
							(end 0.2032 0.3048)
						)
						(arc
							(start -0.2032 0.3048)
							(mid -0.275042 0.275042)
							(end -0.3048 0.2032)
						)
						(arc
							(start -0.3048 -0.2032)
							(mid -0.275042 -0.275042)
							(end -0.2032 -0.3048)
						)
						(arc
							(start 0.2032 -0.3048)
							(mid 0.275042 -0.275042)
							(end 0.3048 -0.2032)
						)
					)
					(width 0)
					(fill yes)
				)
			)
		)
		(pad "2" smd custom
			(at 0 0.4445 180)
			(size 0.1524 0.1524)
			(layers "B.Cu" "B.Mask" "B.Paste")
			(net "GND")
			(options
				(clearance outline)
				(anchor circle)
			)
			(primitives
				(gr_poly
					(pts
						(arc
							(start 0.3048 0.2032)
							(mid 0.275042 0.275042)
							(end 0.2032 0.3048)
						)
						(arc
							(start -0.2032 0.3048)
							(mid -0.275042 0.275042)
							(end -0.3048 0.2032)
						)
						(arc
							(start -0.3048 -0.2032)
							(mid -0.275042 -0.275042)
							(end -0.2032 -0.3048)
						)
						(arc
							(start 0.2032 -0.3048)
							(mid 0.275042 -0.275042)
							(end 0.3048 -0.2032)
						)
					)
					(width 0)
					(fill yes)
				)
			)
		)
	)
	(footprint ""
		(layer "B.Cu")
		(at 189.2681 -62.1919 90)
		(property "Reference" "C404"
			(at 0 0 90)
			(layer "B.SilkS")
			(hide yes)
			(effects
				(font
					(size 1.27 1.27)
				)
				(justify mirror)
			)
		)
		(property "Value" "SCD1U6D3V1KX-GP"
			(at 2.8321 -1.7399 90)
			(unlocked yes)
			(layer "B.Fab")
			(hide yes)
			(effects
				(font
					(size 1.016 1.016)
					(thickness 0.1524)
				)
				(justify mirror)
			)
		)
		(property "Device Type" "C0201H13"
			(at 2.8321 -3.2639 90)
			(unlocked yes)
			(layer "B.Fab")
			(hide yes)
			(effects
				(font
					(size 1.016 1.016)
					(thickness 0.1524)
				)
				(justify mirror)
			)
		)
		(duplicate_pad_numbers_are_jumpers no)
		(fp_rect
			(start 0.2794 0.6477)
			(end -0.2794 -0.6477)
			(stroke
				(width 0)
				(type default)
			)
			(fill no)
			(layer "B.CrtYd")
		)
		(fp_rect
			(start 0.2794 0.6477)
			(end -0.2794 -0.6477)
			(stroke
				(width 0)
				(type default)
			)
			(fill no)
			(layer "B.Fab")
		)
		(pad "1" smd custom
			(at 0 -0.2794 270)
			(size 0.0762 0.0762)
			(layers "B.Cu" "B.Mask" "B.Paste")
			(net "P0V975")
			(options
				(clearance outline)
				(anchor circle)
			)
			(primitives
				(gr_poly
					(pts
						(arc
							(start 0.1524 0.127)
							(mid 0.137521 0.162921)
							(end 0.1016 0.1778)
						)
						(arc
							(start -0.1016 0.1778)
							(mid -0.137521 0.162921)
							(end -0.1524 0.127)
						)
						(arc
							(start -0.1524 -0.127)
							(mid -0.137521 -0.162921)
							(end -0.1016 -0.1778)
						)
						(arc
							(start 0.1016 -0.1778)
							(mid 0.137521 -0.162921)
							(end 0.1524 -0.127)
						)
					)
					(width 0)
					(fill yes)
				)
			)
		)
		(pad "2" smd custom
			(at 0 0.2794 270)
			(size 0.0762 0.0762)
			(layers "B.Cu" "B.Mask" "B.Paste")
			(net "GND")
			(options
				(clearance outline)
				(anchor circle)
			)
			(primitives
				(gr_poly
					(pts
						(arc
							(start 0.1524 0.127)
							(mid 0.137521 0.162921)
							(end 0.1016 0.1778)
						)
						(arc
							(start -0.1016 0.1778)
							(mid -0.137521 0.162921)
							(end -0.1524 0.127)
						)
						(arc
							(start -0.1524 -0.127)
							(mid -0.137521 -0.162921)
							(end -0.1016 -0.1778)
						)
						(arc
							(start 0.1016 -0.1778)
							(mid 0.137521 -0.162921)
							(end 0.1524 -0.127)
						)
					)
					(width 0)
					(fill yes)
				)
			)
		)
	)
	(footprint ""
		(layer "B.Cu")
		(at 43.4848 -133.1214 180)
		(property "Reference" "R374"
			(at 0 0 0)
			(layer "B.SilkS")
			(hide yes)
			(effects
				(font
					(size 1.27 1.27)
				)
				(justify mirror)
			)
		)
		(property "Value" "4K7R2F-GP"
			(at -0.064008 -3.993896 180)
			(unlocked yes)
			(layer "B.Fab")
			(hide yes)
			(effects
				(font
					(size 1.016 1.016)
					(thickness 0.1524)
				)
				(justify mirror)
			)
		)
		(property "Device Type" "R402H16"
			(at -0.064008 -5.517896 180)
			(unlocked yes)
			(layer "B.Fab")
			(hide yes)
			(effects
				(font
					(size 1.016 1.016)
					(thickness 0.1524)
				)
				(justify mirror)
			)
		)
		(duplicate_pad_numbers_are_jumpers no)
		(fp_line
			(start 0.508 -0.9398)
			(end 0.508 0.9398)
			(stroke
				(width 0.1524)
				(type default)
			)
			(layer "B.SilkS")
		)
		(fp_line
			(start -0.508 -0.9398)
			(end 0.508 -0.9398)
			(stroke
				(width 0.1524)
				(type default)
			)
			(layer "B.SilkS")
		)
		(fp_rect
			(start 0.508 0.9398)
			(end -0.508 -0.9398)
			(stroke
				(width 0)
				(type default)
			)
			(fill no)
			(layer "B.CrtYd")
		)
		(fp_rect
			(start 0.508 0.9398)
			(end -0.508 -0.9398)
			(stroke
				(width 0)
				(type default)
			)
			(fill no)
			(layer "B.Fab")
		)
		(pad "1" smd custom
			(at 0 -0.4445)
			(size 0.1397 0.1397)
			(layers "B.Cu" "B.Mask" "B.Paste")
			(net "P3V3_STBY")
			(options
				(clearance outline)
				(anchor circle)
			)
			(primitives
				(gr_poly
					(pts
						(arc
							(start -0.1778 0.2794)
							(mid -0.249642 0.249642)
							(end -0.2794 0.1778)
						)
						(arc
							(start -0.2794 -0.1778)
							(mid -0.249642 -0.249642)
							(end -0.1778 -0.2794)
						)
						(arc
							(start 0.1778 -0.2794)
							(mid 0.249642 -0.249642)
							(end 0.2794 -0.1778)
						)
						(arc
							(start 0.2794 0.1778)
							(mid 0.249642 0.249642)
							(end 0.1778 0.2794)
						)
					)
					(width 0)
					(fill yes)
				)
			)
		)
		(pad "2" smd custom
			(at 0 0.4445)
			(size 0.1397 0.1397)
			(layers "B.Cu" "B.Mask" "B.Paste")
			(net "BMC_GPIOS6")
			(options
				(clearance outline)
				(anchor circle)
			)
			(primitives
				(gr_poly
					(pts
						(arc
							(start -0.1778 0.2794)
							(mid -0.249642 0.249642)
							(end -0.2794 0.1778)
						)
						(arc
							(start -0.2794 -0.1778)
							(mid -0.249642 -0.249642)
							(end -0.1778 -0.2794)
						)
						(arc
							(start 0.1778 -0.2794)
							(mid 0.249642 -0.249642)
							(end 0.2794 -0.1778)
						)
						(arc
							(start 0.2794 0.1778)
							(mid 0.249642 0.249642)
							(end 0.1778 0.2794)
						)
					)
					(width 0)
					(fill yes)
				)
			)
		)
	)
)
